# T6G (Grand Teton) — schematic netlist excerpt (pin names and nets, part order shuffled) for the footprints in the layout excerpt that follows; sources: Cadence DE-HDL packaged netlist, KiCad conversion of 04192023_DAF0TMB3IC0_F0TG_MB_C_brd_V02_OCP.brd

PC6002  Q_CAP  0.1UF 25V 10% X7R  pkg 0402  page 226 : A = P12V_AUX ; B = GND
R8146  Q_RES  0 5% EMPTY  pkg 0402LF  page 224 : A = P3V3_AUX ; B = PVDD11_S3_P1_VDDIO
R1395  Q_RES  4.7K 5% CHIP  pkg 0201LF  page 287 : A = CLKREQ_RT_CPU0_P1_N ; B = GND

(kicad_pcb
	(version 20260206)
	(generator "pcbnew")
	(generator_version "10.0")
	(general
		(thickness 1.6)
		(legacy_teardrops no)
	)
	(paper "A4")
	(title_block
		(title "04192023_DAF0TMB3IC0_F0TG_MB_C_brd_V02_OCP.brd")
		(comment 1 "Grand Teton / footprints 4040-4042 of 8354")
	)
	(layers
		(0 "F.Cu" signal "TOP")
		(4 "In1.Cu" signal "GND")
		(6 "In2.Cu" signal "IN1")
		(8 "In3.Cu" signal "GND1")
		(10 "In4.Cu" signal "IN2")
		(12 "In5.Cu" signal "GND2")
		(14 "In6.Cu" signal "IN3")
		(16 "In7.Cu" signal "GND3")
		(18 "In8.Cu" signal "VCC")
		(20 "In9.Cu" signal "VCC1")
		(22 "In10.Cu" signal "GND4")
		(24 "In11.Cu" signal "IN4")
		(26 "In12.Cu" signal "GND5")
		(28 "In13.Cu" signal "IN5")
		(30 "In14.Cu" signal "GND6")
		(32 "In15.Cu" signal "IN6")
		(34 "In16.Cu" signal "GND7")
		(2 "B.Cu" signal "BOTTOM")
		(9 "F.Adhes" user "F.Adhesive")
		(11 "B.Adhes" user "B.Adhesive")
		(13 "F.Paste" user "Package Geometry/Pastemask Top")
		(15 "B.Paste" user "Package Geometry/Pastemask Bottom")
		(5 "F.SilkS" user "Ref Des/Silkscreen Top")
		(7 "B.SilkS" user "Ref Des/Silkscreen Bottom")
		(1 "F.Mask" user "Board Geometry/Soldermask Top")
		(3 "B.Mask" user "Board Geometry/Soldermask Bottom")
		(17 "Dwgs.User" user "User.Drawings")
		(19 "Cmts.User" user "User.Comments")
		(21 "Eco1.User" user "User.Eco1")
		(23 "Eco2.User" user "User.Eco2")
		(25 "Edge.Cuts" user "Board Geometry/Outline")
		(27 "Margin" user)
		(31 "F.CrtYd" user "Package Geometry/Place Bound Top")
		(29 "B.CrtYd" user "Package Geometry/Place Bound Bottom")
		(35 "F.Fab" user "Ref Des/Assembly Top")
		(33 "B.Fab" user "Ref Des/Assembly Bottom")
	)
	(footprint ""
		(layer "F.Cu")
		(at 157.698186 -347.260164)
		(property "Reference" "R8146"
			(at 0 0 0)
			(layer "F.SilkS")
			(hide yes)
			(effects
				(font
					(size 1.27 1.27)
				)
			)
		)
		(property "Value" ""
			(at 0 0 0)
			(layer "F.Fab")
			(effects
				(font
					(size 1.27 1.27)
				)
			)
		)
		(duplicate_pad_numbers_are_jumpers no)
		(fp_line
			(start -0.7874 -0.4064)
			(end 0.7874 -0.4064)
			(stroke
				(width 0.1524)
				(type default)
			)
			(layer "F.SilkS")
		)
		(fp_line
			(start -0.7874 0.4064)
			(end -0.7874 -0.4064)
			(stroke
				(width 0.1524)
				(type default)
			)
			(layer "F.SilkS")
		)
		(fp_line
			(start 0.7874 -0.4064)
			(end 0.7874 0.4064)
			(stroke
				(width 0.1524)
				(type default)
			)
			(layer "F.SilkS")
		)
		(fp_line
			(start 0.7874 0.4064)
			(end -0.7874 0.4064)
			(stroke
				(width 0.1524)
				(type default)
			)
			(layer "F.SilkS")
		)
		(fp_line
			(start -0.67945 -0.305054)
			(end -0.12065 -0.305054)
			(stroke
				(width 0.1)
				(type default)
			)
			(layer "F.Fab")
		)
		(fp_line
			(start -0.67945 0.3048)
			(end -0.67945 -0.305054)
			(stroke
				(width 0.1)
				(type default)
			)
			(layer "F.Fab")
		)
		(fp_line
			(start -0.12065 -0.305054)
			(end -0.12065 -0.2794)
			(stroke
				(width 0.1)
				(type default)
			)
			(layer "F.Fab")
		)
		(fp_line
			(start -0.12065 -0.2794)
			(end 0.12065 -0.2794)
			(stroke
				(width 0.1)
				(type default)
			)
			(layer "F.Fab")
		)
		(fp_line
			(start -0.12065 0.2794)
			(end -0.12065 0.3048)
			(stroke
				(width 0.1)
				(type default)
			)
			(layer "F.Fab")
		)
		(fp_line
			(start -0.12065 0.3048)
			(end -0.67945 0.3048)
			(stroke
				(width 0.1)
				(type default)
			)
			(layer "F.Fab")
		)
		(fp_line
			(start 0.120396 0.2794)
			(end -0.12065 0.2794)
			(stroke
				(width 0.1)
				(type default)
			)
			(layer "F.Fab")
		)
		(fp_line
			(start 0.120396 0.3048)
			(end 0.120396 0.2794)
			(stroke
				(width 0.1)
				(type default)
			)
			(layer "F.Fab")
		)
		(fp_line
			(start 0.12065 -0.3048)
			(end 0.67945 -0.3048)
			(stroke
				(width 0.1)
				(type default)
			)
			(layer "F.Fab")
		)
		(fp_line
			(start 0.12065 -0.2794)
			(end 0.12065 -0.3048)
			(stroke
				(width 0.1)
				(type default)
			)
			(layer "F.Fab")
		)
		(fp_line
			(start 0.67945 -0.3048)
			(end 0.67945 0.3048)
			(stroke
				(width 0.1)
				(type default)
			)
			(layer "F.Fab")
		)
		(fp_line
			(start 0.67945 0.3048)
			(end 0.120396 0.3048)
			(stroke
				(width 0.1)
				(type default)
			)
			(layer "F.Fab")
		)
		(pad "1" smd circle
			(at -0.40005 0)
			(size 0 0)
			(layers "F.Cu" "F.Mask" "F.Paste")
			(net "P3V3_AUX")
		)
		(pad "2" smd circle
			(at 0.40005 0)
			(size 0 0)
			(layers "F.Cu" "F.Mask" "F.Paste")
			(net "PVDD11_S3_P1_VDDIO")
		)
	)
	(footprint ""
		(layer "F.Cu")
		(at 358.96169 -390.1694 180)
		(property "Reference" "R1395"
			(at 0 0 180)
			(layer "F.SilkS")
			(hide yes)
			(effects
				(font
					(size 1.27 1.27)
				)
			)
		)
		(property "Value" ""
			(at 0 0 180)
			(layer "F.Fab")
			(effects
				(font
					(size 1.27 1.27)
				)
			)
		)
		(duplicate_pad_numbers_are_jumpers no)
		(fp_line
			(start 0.32512 0.175006)
			(end -0.32512 0.175006)
			(stroke
				(width 0.1)
				(type default)
			)
			(layer "F.Fab")
		)
		(fp_line
			(start 0.32512 -0.175006)
			(end 0.32512 0.175006)
			(stroke
				(width 0.1)
				(type default)
			)
			(layer "F.Fab")
		)
		(fp_line
			(start -0.32512 0.175006)
			(end -0.32512 -0.175006)
			(stroke
				(width 0.1)
				(type default)
			)
			(layer "F.Fab")
		)
		(fp_line
			(start -0.32512 -0.175006)
			(end 0.32512 -0.175006)
			(stroke
				(width 0.1)
				(type default)
			)
			(layer "F.Fab")
		)
		(pad "1" smd rect
			(at -0.2667 0 180)
			(size 0.3048 0.381)
			(layers "F.Cu" "F.Mask" "F.Paste")
			(net "CLKREQ_RT_CPU0_P1_N")
		)
		(pad "2" smd rect
			(at 0.2667 0)
			(size 0.3048 0.381)
			(layers "F.Cu" "F.Mask" "F.Paste")
			(net "GND")
		)
	)
	(footprint ""
		(layer "F.Cu")
		(at 84.832952 -151.207216 -90)
		(property "Reference" "PC6002"
			(at 0 0 270)
			(layer "F.SilkS")
			(hide yes)
			(effects
				(font
					(size 1.27 1.27)
				)
			)
		)
		(property "Value" ""
			(at 0 0 270)
			(layer "F.Fab")
			(effects
				(font
					(size 1.27 1.27)
				)
			)
		)
		(duplicate_pad_numbers_are_jumpers no)
		(fp_line
			(start -0.7874 0.4064)
			(end -0.7874 -0.4064)
			(stroke
				(width 0.1524)
				(type default)
			)
			(layer "F.SilkS")
		)
		(fp_line
			(start 0.7874 0.4064)
			(end -0.7874 0.4064)
			(stroke
				(width 0.1524)
				(type default)
			)
			(layer "F.SilkS")
		)
		(fp_line
			(start -0.7874 -0.4064)
			(end 0.7874 -0.4064)
			(stroke
				(width 0.1524)
				(type default)
			)
			(layer "F.SilkS")
		)
		(fp_line
			(start 0.7874 -0.4064)
			(end 0.7874 0.4064)
			(stroke
				(width 0.1524)
				(type default)
			)
			(layer "F.SilkS")
		)
		(fp_line
			(start -0.67945 0.3048)
			(end -0.67945 -0.305054)
			(stroke
				(width 0.1)
				(type default)
			)
			(layer "F.Fab")
		)
		(fp_line
			(start -0.12065 0.3048)
			(end -0.67945 0.3048)
			(stroke
				(width 0.1)
				(type default)
			)
			(layer "F.Fab")
		)
		(fp_line
			(start 0.120396 0.3048)
			(end 0.120396 0.2794)
			(stroke
				(width 0.1)
				(type default)
			)
			(layer "F.Fab")
		)
		(fp_line
			(start 0.67945 0.3048)
			(end 0.120396 0.3048)
			(stroke
				(width 0.1)
				(type default)
			)
			(layer "F.Fab")
		)
		(fp_line
			(start -0.12065 0.2794)
			(end -0.12065 0.3048)
			(stroke
				(width 0.1)
				(type default)
			)
			(layer "F.Fab")
		)
		(fp_line
			(start 0.120396 0.2794)
			(end -0.12065 0.2794)
			(stroke
				(width 0.1)
				(type default)
			)
			(layer "F.Fab")
		)
		(fp_line
			(start -0.12065 -0.2794)
			(end 0.12065 -0.2794)
			(stroke
				(width 0.1)
				(type default)
			)
			(layer "F.Fab")
		)
		(fp_line
			(start 0.12065 -0.2794)
			(end 0.12065 -0.3048)
			(stroke
				(width 0.1)
				(type default)
			)
			(layer "F.Fab")
		)
		(fp_line
			(start 0.12065 -0.3048)
			(end 0.67945 -0.3048)
			(stroke
				(width 0.1)
				(type default)
			)
			(layer "F.Fab")
		)
		(fp_line
			(start 0.67945 -0.3048)
			(end 0.67945 0.3048)
			(stroke
				(width 0.1)
				(type default)
			)
			(layer "F.Fab")
		)
		(fp_line
			(start -0.67945 -0.305054)
			(end -0.12065 -0.305054)
			(stroke
				(width 0.1)
				(type default)
			)
			(layer "F.Fab")
		)
		(fp_line
			(start -0.12065 -0.305054)
			(end -0.12065 -0.2794)
			(stroke
				(width 0.1)
				(type default)
			)
			(layer "F.Fab")
		)
		(pad "1" smd circle
			(at -0.40005 0 270)
			(size 0 0)
			(layers "F.Cu" "F.Mask" "F.Paste")
			(net "P12V_AUX")
		)
		(pad "2" smd circle
			(at 0.40005 0 270)
			(size 0 0)
			(layers "F.Cu" "F.Mask" "F.Paste")
			(net "GND")
		)
	)
)
